(kicad_pcb
	(version 20260206)
	(generator "pcbnew")
	(generator_version "10.0")
	(general
		(thickness 1.6)
		(legacy_teardrops no)
	)
	(paper "A4")
	(title_block
		(title "04192023_DAF0TMB3IC0_F0TG_MB_C_brd_V02_OCP.brd")
		(comment 1 "Grand Teton / footprint 2165 of 8354 (J20), pads 1-113 of 291")
	)
	(layers
		(0 "F.Cu" signal "TOP")
		(4 "In1.Cu" signal "GND")
		(6 "In2.Cu" signal "IN1")
		(8 "In3.Cu" signal "GND1")
		(10 "In4.Cu" signal "IN2")
		(12 "In5.Cu" signal "GND2")
		(14 "In6.Cu" signal "IN3")
		(16 "In7.Cu" signal "GND3")
		(18 "In8.Cu" signal "VCC")
		(20 "In9.Cu" signal "VCC1")
		(22 "In10.Cu" signal "GND4")
		(24 "In11.Cu" signal "IN4")
		(26 "In12.Cu" signal "GND5")
		(28 "In13.Cu" signal "IN5")
		(30 "In14.Cu" signal "GND6")
		(32 "In15.Cu" signal "IN6")
		(34 "In16.Cu" signal "GND7")
		(2 "B.Cu" signal "BOTTOM")
		(9 "F.Adhes" user "F.Adhesive")
		(11 "B.Adhes" user "B.Adhesive")
		(13 "F.Paste" user "Package Geometry/Pastemask Top")
		(15 "B.Paste" user "Package Geometry/Pastemask Bottom")
		(5 "F.SilkS" user "Ref Des/Silkscreen Top")
		(7 "B.SilkS" user "Ref Des/Silkscreen Bottom")
		(1 "F.Mask" user "Board Geometry/Soldermask Top")
		(3 "B.Mask" user "Board Geometry/Soldermask Bottom")
		(17 "Dwgs.User" user "User.Drawings")
		(19 "Cmts.User" user "User.Comments")
		(21 "Eco1.User" user "User.Eco1")
		(23 "Eco2.User" user "User.Eco2")
		(25 "Edge.Cuts" user "Board Geometry/Outline")
		(27 "Margin" user)
		(31 "F.CrtYd" user "Package Geometry/Place Bound Top")
		(29 "B.CrtYd" user "Package Geometry/Place Bound Bottom")
		(35 "F.Fab" user "Ref Des/Assembly Top")
		(33 "B.Fab" user "Ref Des/Assembly Bottom")
	)
	(footprint ""
		(layer "F.Cu")
		(at 444.594234 -255.560068 180)
		(property "Reference" "J20"
			(at 1.631188 -81.796128 0)
			(unlocked yes)
			(layer "F.SilkS")
			(effects
				(font
					(size 0.7874 0.5842)
					(thickness 0.1524)
				)
			)
		)
		(property "Value" ""
			(at 0 0 180)
			(layer "F.Fab")
			(effects
				(font
					(size 1.27 1.27)
				)
			)
		)
		(duplicate_pad_numbers_are_jumpers no)
		(pad "1" smd rect
			(at -2.050034 -63.324994 90)
			(size 0.519938 1.4986)
			(layers "F.Cu" "F.Mask" "F.Paste")
			(net "P12V_MEM_CPU0")
		)
		(pad "2" smd rect
			(at -2.050034 -62.47511 90)
			(size 0.519938 1.4986)
			(layers "F.Cu" "F.Mask" "F.Paste")
			(net "Net_2389")
		)
		(pad "3" smd rect
			(at -2.050034 -61.624972 90)
			(size 0.519938 1.4986)
			(layers "F.Cu" "F.Mask" "F.Paste")
			(net "P3V3_AUX")
		)
		(pad "4" smd rect
			(at -2.050034 -60.775088 90)
			(size 0.519938 1.4986)
			(layers "F.Cu" "F.Mask" "F.Paste")
			(net "I3C_SPD_DDRK_CPU0_SCL")
		)
		(pad "5" smd rect
			(at -2.050034 -59.92495 90)
			(size 0.519938 1.4986)
			(layers "F.Cu" "F.Mask" "F.Paste")
			(net "I3C_SPD_DDRK_CPU0_SDA")
		)
		(pad "6" smd rect
			(at -2.050034 -59.075066 90)
			(size 0.519938 1.4986)
			(layers "F.Cu" "F.Mask" "F.Paste")
			(net "GND")
		)
		(pad "7" smd rect
			(at -2.050034 -58.224928 90)
			(size 0.519938 1.4986)
			(layers "F.Cu" "F.Mask" "F.Paste")
			(net "M_K_CPU0_SA_DQ<0>")
		)
		(pad "8" smd rect
			(at -2.050034 -57.375044 90)
			(size 0.519938 1.4986)
			(layers "F.Cu" "F.Mask" "F.Paste")
			(net "GND")
		)
		(pad "9" smd rect
			(at -2.050034 -56.524906 90)
			(size 0.519938 1.4986)
			(layers "F.Cu" "F.Mask" "F.Paste")
			(net "M_K_CPU0_SA_DQ<1>")
		)
		(pad "10" smd rect
			(at -2.050034 -55.675022 90)
			(size 0.519938 1.4986)
			(layers "F.Cu" "F.Mask" "F.Paste")
			(net "GND")
		)
		(pad "11" smd rect
			(at -2.050034 -54.824884 90)
			(size 0.519938 1.4986)
			(layers "F.Cu" "F.Mask" "F.Paste")
			(net "M_K_CPU0_SA_DQS_DP<0>")
		)
		(pad "12" smd rect
			(at -2.050034 -53.975 90)
			(size 0.519938 1.4986)
			(layers "F.Cu" "F.Mask" "F.Paste")
			(net "M_K_CPU0_SA_DQS_DN<0>")
		)
		(pad "13" smd rect
			(at -2.050034 -53.125116 90)
			(size 0.519938 1.4986)
			(layers "F.Cu" "F.Mask" "F.Paste")
			(net "GND")
		)
		(pad "14" smd rect
			(at -2.050034 -52.274978 90)
			(size 0.519938 1.4986)
			(layers "F.Cu" "F.Mask" "F.Paste")
			(net "M_K_CPU0_SA_DQ<4>")
		)
		(pad "15" smd rect
			(at -2.050034 -51.425094 90)
			(size 0.519938 1.4986)
			(layers "F.Cu" "F.Mask" "F.Paste")
			(net "GND")
		)
		(pad "16" smd rect
			(at -2.050034 -50.574956 90)
			(size 0.519938 1.4986)
			(layers "F.Cu" "F.Mask" "F.Paste")
			(net "M_K_CPU0_SA_DQ<5>")
		)
		(pad "17" smd rect
			(at -2.050034 -49.725072 90)
			(size 0.519938 1.4986)
			(layers "F.Cu" "F.Mask" "F.Paste")
			(net "GND")
		)
		(pad "18" smd rect
			(at -2.050034 -48.874934 90)
			(size 0.519938 1.4986)
			(layers "F.Cu" "F.Mask" "F.Paste")
			(net "M_K_CPU0_SA_DQ<8>")
		)
		(pad "19" smd rect
			(at -2.050034 -48.02505 90)
			(size 0.519938 1.4986)
			(layers "F.Cu" "F.Mask" "F.Paste")
			(net "GND")
		)
		(pad "20" smd rect
			(at -2.050034 -47.174912 90)
			(size 0.519938 1.4986)
			(layers "F.Cu" "F.Mask" "F.Paste")
			(net "M_K_CPU0_SA_DQ<9>")
		)
		(pad "21" smd rect
			(at -2.050034 -46.325028 90)
			(size 0.519938 1.4986)
			(layers "F.Cu" "F.Mask" "F.Paste")
			(net "GND")
		)
		(pad "22" smd rect
			(at -2.050034 -45.47489 90)
			(size 0.519938 1.4986)
			(layers "F.Cu" "F.Mask" "F.Paste")
			(net "M_K_CPU0_SA_DQS_DP<1>")
		)
		(pad "23" smd rect
			(at -2.050034 -44.625006 90)
			(size 0.519938 1.4986)
			(layers "F.Cu" "F.Mask" "F.Paste")
			(net "M_K_CPU0_SA_DQS_DN<1>")
		)
		(pad "24" smd rect
			(at -2.050034 -43.775122 90)
			(size 0.519938 1.4986)
			(layers "F.Cu" "F.Mask" "F.Paste")
			(net "GND")
		)
		(pad "25" smd rect
			(at -2.050034 -42.924984 90)
			(size 0.519938 1.4986)
			(layers "F.Cu" "F.Mask" "F.Paste")
			(net "M_K_CPU0_SA_DQ<12>")
		)
		(pad "26" smd rect
			(at -2.050034 -42.0751 90)
			(size 0.519938 1.4986)
			(layers "F.Cu" "F.Mask" "F.Paste")
			(net "GND")
		)
		(pad "27" smd rect
			(at -2.050034 -41.224962 90)
			(size 0.519938 1.4986)
			(layers "F.Cu" "F.Mask" "F.Paste")
			(net "M_K_CPU0_SA_DQ<13>")
		)
		(pad "28" smd rect
			(at -2.050034 -40.375078 90)
			(size 0.519938 1.4986)
			(layers "F.Cu" "F.Mask" "F.Paste")
			(net "GND")
		)
		(pad "29" smd rect
			(at -2.050034 -39.52494 90)
			(size 0.519938 1.4986)
			(layers "F.Cu" "F.Mask" "F.Paste")
			(net "M_K_CPU0_SA_DQ<16>")
		)
		(pad "30" smd rect
			(at -2.050034 -38.675056 90)
			(size 0.519938 1.4986)
			(layers "F.Cu" "F.Mask" "F.Paste")
			(net "GND")
		)
		(pad "31" smd rect
			(at -2.050034 -37.824918 90)
			(size 0.519938 1.4986)
			(layers "F.Cu" "F.Mask" "F.Paste")
			(net "M_K_CPU0_SA_DQ<17>")
		)
		(pad "32" smd rect
			(at -2.050034 -36.975034 90)
			(size 0.519938 1.4986)
			(layers "F.Cu" "F.Mask" "F.Paste")
			(net "GND")
		)
		(pad "33" smd rect
			(at -2.050034 -36.124896 90)
			(size 0.519938 1.4986)
			(layers "F.Cu" "F.Mask" "F.Paste")
			(net "M_K_CPU0_SA_DQS_DP<2>")
		)
		(pad "34" smd rect
			(at -2.050034 -35.275012 90)
			(size 0.519938 1.4986)
			(layers "F.Cu" "F.Mask" "F.Paste")
			(net "M_K_CPU0_SA_DQS_DN<2>")
		)
		(pad "35" smd rect
			(at -2.050034 -34.425128 90)
			(size 0.519938 1.4986)
			(layers "F.Cu" "F.Mask" "F.Paste")
			(net "GND")
		)
		(pad "36" smd rect
			(at -2.050034 -33.57499 90)
			(size 0.519938 1.4986)
			(layers "F.Cu" "F.Mask" "F.Paste")
			(net "M_K_CPU0_SA_DQ<20>")
		)
		(pad "37" smd rect
			(at -2.050034 -32.725106 90)
			(size 0.519938 1.4986)
			(layers "F.Cu" "F.Mask" "F.Paste")
			(net "GND")
		)
		(pad "38" smd rect
			(at -2.050034 -31.874968 90)
			(size 0.519938 1.4986)
			(layers "F.Cu" "F.Mask" "F.Paste")
			(net "M_K_CPU0_SA_DQ<21>")
		)
		(pad "39" smd rect
			(at -2.050034 -31.025084 90)
			(size 0.519938 1.4986)
			(layers "F.Cu" "F.Mask" "F.Paste")
			(net "GND")
		)
		(pad "40" smd rect
			(at -2.050034 -30.174946 90)
			(size 0.519938 1.4986)
			(layers "F.Cu" "F.Mask" "F.Paste")
			(net "M_K_CPU0_SA_DQ<24>")
		)
		(pad "41" smd rect
			(at -2.050034 -29.325062 90)
			(size 0.519938 1.4986)
			(layers "F.Cu" "F.Mask" "F.Paste")
			(net "GND")
		)
		(pad "42" smd rect
			(at -2.050034 -28.474924 90)
			(size 0.519938 1.4986)
			(layers "F.Cu" "F.Mask" "F.Paste")
			(net "M_K_CPU0_SA_DQ<25>")
		)
		(pad "43" smd rect
			(at -2.050034 -27.62504 90)
			(size 0.519938 1.4986)
			(layers "F.Cu" "F.Mask" "F.Paste")
			(net "GND")
		)
		(pad "44" smd rect
			(at -2.050034 -26.774902 90)
			(size 0.519938 1.4986)
			(layers "F.Cu" "F.Mask" "F.Paste")
			(net "M_K_CPU0_SA_DQS_DP<3>")
		)
		(pad "45" smd rect
			(at -2.050034 -25.925018 90)
			(size 0.519938 1.4986)
			(layers "F.Cu" "F.Mask" "F.Paste")
			(net "M_K_CPU0_SA_DQS_DN<3>")
		)
		(pad "46" smd rect
			(at -2.050034 -25.07488 90)
			(size 0.519938 1.4986)
			(layers "F.Cu" "F.Mask" "F.Paste")
			(net "GND")
		)
		(pad "47" smd rect
			(at -2.050034 -24.224996 90)
			(size 0.519938 1.4986)
			(layers "F.Cu" "F.Mask" "F.Paste")
			(net "M_K_CPU0_SA_DQ<28>")
		)
		(pad "48" smd rect
			(at -2.050034 -23.375112 90)
			(size 0.519938 1.4986)
			(layers "F.Cu" "F.Mask" "F.Paste")
			(net "GND")
		)
		(pad "49" smd rect
			(at -2.050034 -22.524974 90)
			(size 0.519938 1.4986)
			(layers "F.Cu" "F.Mask" "F.Paste")
			(net "M_K_CPU0_SA_DQ<29>")
		)
		(pad "50" smd rect
			(at -2.050034 -21.67509 90)
			(size 0.519938 1.4986)
			(layers "F.Cu" "F.Mask" "F.Paste")
			(net "GND")
		)
		(pad "51" smd rect
			(at -2.050034 -20.824952 90)
			(size 0.519938 1.4986)
			(layers "F.Cu" "F.Mask" "F.Paste")
			(net "M_K_CPU0_SA_CB<0>")
		)
		(pad "52" smd rect
			(at -2.050034 -19.975068 90)
			(size 0.519938 1.4986)
			(layers "F.Cu" "F.Mask" "F.Paste")
			(net "GND")
		)
		(pad "53" smd rect
			(at -2.050034 -19.12493 90)
			(size 0.519938 1.4986)
			(layers "F.Cu" "F.Mask" "F.Paste")
			(net "M_K_CPU0_SA_CB<1>")
		)
		(pad "54" smd rect
			(at -2.050034 -18.275046 90)
			(size 0.519938 1.4986)
			(layers "F.Cu" "F.Mask" "F.Paste")
			(net "GND")
		)
		(pad "55" smd rect
			(at -2.050034 -17.424908 90)
			(size 0.519938 1.4986)
			(layers "F.Cu" "F.Mask" "F.Paste")
			(net "M_K_CPU0_SA_DQS_DP<4>")
		)
		(pad "56" smd rect
			(at -2.050034 -16.575024 90)
			(size 0.519938 1.4986)
			(layers "F.Cu" "F.Mask" "F.Paste")
			(net "M_K_CPU0_SA_DQS_DN<4>")
		)
		(pad "57" smd rect
			(at -2.050034 -15.724886 90)
			(size 0.519938 1.4986)
			(layers "F.Cu" "F.Mask" "F.Paste")
			(net "GND")
		)
		(pad "58" smd rect
			(at -2.050034 -14.875002 90)
			(size 0.519938 1.4986)
			(layers "F.Cu" "F.Mask" "F.Paste")
			(net "M_K_CPU0_SA_CB<4>")
		)
		(pad "59" smd rect
			(at -2.050034 -14.025118 90)
			(size 0.519938 1.4986)
			(layers "F.Cu" "F.Mask" "F.Paste")
			(net "GND")
		)
		(pad "60" smd rect
			(at -2.050034 -13.17498 90)
			(size 0.519938 1.4986)
			(layers "F.Cu" "F.Mask" "F.Paste")
			(net "M_K_CPU0_SA_CB<5>")
		)
		(pad "61" smd rect
			(at -2.050034 -12.325096 90)
			(size 0.519938 1.4986)
			(layers "F.Cu" "F.Mask" "F.Paste")
			(net "GND")
		)
		(pad "62" smd rect
			(at -2.050034 -11.474958 90)
			(size 0.519938 1.4986)
			(layers "F.Cu" "F.Mask" "F.Paste")
			(net "M_K_CPU0_ALERT_N")
		)
		(pad "63" smd rect
			(at -2.050034 -10.625074 90)
			(size 0.519938 1.4986)
			(layers "F.Cu" "F.Mask" "F.Paste")
			(net "GND")
		)
		(pad "64" smd rect
			(at -2.050034 -9.774936 90)
			(size 0.519938 1.4986)
			(layers "F.Cu" "F.Mask" "F.Paste")
			(net "M_K_CPU0_SA_CS_N<0>")
		)
		(pad "65" smd rect
			(at -2.050034 -8.925052 90)
			(size 0.519938 1.4986)
			(layers "F.Cu" "F.Mask" "F.Paste")
			(net "GND")
		)
		(pad "66" smd rect
			(at -2.050034 -8.074914 90)
			(size 0.519938 1.4986)
			(layers "F.Cu" "F.Mask" "F.Paste")
			(net "M_K_CPU0_SA_CA<0>")
		)
		(pad "67" smd rect
			(at -2.050034 -7.22503 90)
			(size 0.519938 1.4986)
			(layers "F.Cu" "F.Mask" "F.Paste")
			(net "GND")
		)
		(pad "68" smd rect
			(at -2.050034 -6.374892 90)
			(size 0.519938 1.4986)
			(layers "F.Cu" "F.Mask" "F.Paste")
			(net "M_K_CPU0_SA_CA<2>")
		)
		(pad "69" smd rect
			(at -2.050034 -5.525008 90)
			(size 0.519938 1.4986)
			(layers "F.Cu" "F.Mask" "F.Paste")
			(net "GND")
		)
		(pad "70" smd rect
			(at -2.050034 -4.675124 90)
			(size 0.519938 1.4986)
			(layers "F.Cu" "F.Mask" "F.Paste")
			(net "M_K_CPU0_SA_CA<4>")
		)
		(pad "71" smd rect
			(at -2.050034 -3.824986 90)
			(size 0.519938 1.4986)
			(layers "F.Cu" "F.Mask" "F.Paste")
			(net "GND")
		)
		(pad "72" smd rect
			(at -2.050034 -2.975102 90)
			(size 0.519938 1.4986)
			(layers "F.Cu" "F.Mask" "F.Paste")
			(net "M_K_CPU0_SA_CA<6>")
		)
		(pad "73" smd rect
			(at -2.050034 -2.124964 90)
			(size 0.519938 1.4986)
			(layers "F.Cu" "F.Mask" "F.Paste")
			(net "GND")
		)
		(pad "74" smd rect
			(at -2.050034 -1.27508 90)
			(size 0.519938 1.4986)
			(layers "F.Cu" "F.Mask" "F.Paste")
			(net "M_K_CPU0_SA_PAR")
		)
		(pad "75" smd rect
			(at -2.050034 -0.424942 90)
			(size 0.519938 1.4986)
			(layers "F.Cu" "F.Mask" "F.Paste")
			(net "GND")
		)
		(pad "76" smd rect
			(at -2.050034 5.525008 90)
			(size 0.519938 1.4986)
			(layers "F.Cu" "F.Mask" "F.Paste")
			(net "M_K_CPU0_SB_CA<0>")
		)
		(pad "77" smd rect
			(at -2.050034 6.374892 90)
			(size 0.519938 1.4986)
			(layers "F.Cu" "F.Mask" "F.Paste")
			(net "GND")
		)
		(pad "78" smd rect
			(at -2.050034 7.22503 90)
			(size 0.519938 1.4986)
			(layers "F.Cu" "F.Mask" "F.Paste")
			(net "M_K_CPU0_SB_CA<2>")
		)
		(pad "79" smd rect
			(at -2.050034 8.074914 90)
			(size 0.519938 1.4986)
			(layers "F.Cu" "F.Mask" "F.Paste")
			(net "GND")
		)
		(pad "80" smd rect
			(at -2.050034 8.925052 90)
			(size 0.519938 1.4986)
			(layers "F.Cu" "F.Mask" "F.Paste")
			(net "M_K_CPU0_SB_CA<4>")
		)
		(pad "81" smd rect
			(at -2.050034 9.774936 90)
			(size 0.519938 1.4986)
			(layers "F.Cu" "F.Mask" "F.Paste")
			(net "GND")
		)
		(pad "82" smd rect
			(at -2.050034 10.625074 90)
			(size 0.519938 1.4986)
			(layers "F.Cu" "F.Mask" "F.Paste")
			(net "M_K_CPU0_SB_CA<6>")
		)
		(pad "83" smd rect
			(at -2.050034 11.474958 90)
			(size 0.519938 1.4986)
			(layers "F.Cu" "F.Mask" "F.Paste")
			(net "GND")
		)
		(pad "84" smd rect
			(at -2.050034 12.325096 90)
			(size 0.519938 1.4986)
			(layers "F.Cu" "F.Mask" "F.Paste")
			(net "M_K_CPU0_SB_CS_N<0>")
		)
		(pad "85" smd rect
			(at -2.050034 13.17498 90)
			(size 0.519938 1.4986)
			(layers "F.Cu" "F.Mask" "F.Paste")
			(net "GND")
		)
		(pad "86" smd rect
			(at -2.050034 14.025118 90)
			(size 0.519938 1.4986)
			(layers "F.Cu" "F.Mask" "F.Paste")
			(net "M_K_CPU0_SA_RSP<0>")
		)
		(pad "87" smd rect
			(at -2.050034 14.875002 90)
			(size 0.519938 1.4986)
			(layers "F.Cu" "F.Mask" "F.Paste")
			(net "M_K_CPU0_SB_RSP<0>")
		)
		(pad "88" smd rect
			(at -2.050034 15.724886 90)
			(size 0.519938 1.4986)
			(layers "F.Cu" "F.Mask" "F.Paste")
			(net "GND")
		)
		(pad "89" smd rect
			(at -2.050034 16.575024 90)
			(size 0.519938 1.4986)
			(layers "F.Cu" "F.Mask" "F.Paste")
			(net "M_K_CPU0_SB_CB<4>")
		)
		(pad "90" smd rect
			(at -2.050034 17.424908 90)
			(size 0.519938 1.4986)
			(layers "F.Cu" "F.Mask" "F.Paste")
			(net "GND")
		)
		(pad "91" smd rect
			(at -2.050034 18.275046 90)
			(size 0.519938 1.4986)
			(layers "F.Cu" "F.Mask" "F.Paste")
			(net "M_K_CPU0_SB_CB<5>")
		)
		(pad "92" smd rect
			(at -2.050034 19.12493 90)
			(size 0.519938 1.4986)
			(layers "F.Cu" "F.Mask" "F.Paste")
			(net "GND")
		)
		(pad "93" smd rect
			(at -2.050034 19.975068 90)
			(size 0.519938 1.4986)
			(layers "F.Cu" "F.Mask" "F.Paste")
			(net "M_K_CPU0_SB_DQS_DP<9>")
		)
		(pad "94" smd rect
			(at -2.050034 20.824952 90)
			(size 0.519938 1.4986)
			(layers "F.Cu" "F.Mask" "F.Paste")
			(net "M_K_CPU0_SB_DQS_DN<9>")
		)
		(pad "95" smd rect
			(at -2.050034 21.67509 90)
			(size 0.519938 1.4986)
			(layers "F.Cu" "F.Mask" "F.Paste")
			(net "GND")
		)
		(pad "96" smd rect
			(at -2.050034 22.524974 90)
			(size 0.519938 1.4986)
			(layers "F.Cu" "F.Mask" "F.Paste")
			(net "M_K_CPU0_SB_CB<0>")
		)
		(pad "97" smd rect
			(at -2.050034 23.375112 90)
			(size 0.519938 1.4986)
			(layers "F.Cu" "F.Mask" "F.Paste")
			(net "GND")
		)
		(pad "98" smd rect
			(at -2.050034 24.224996 90)
			(size 0.519938 1.4986)
			(layers "F.Cu" "F.Mask" "F.Paste")
			(net "M_K_CPU0_SB_CB<1>")
		)
		(pad "99" smd rect
			(at -2.050034 25.07488 90)
			(size 0.519938 1.4986)
			(layers "F.Cu" "F.Mask" "F.Paste")
			(net "GND")
		)
		(pad "100" smd rect
			(at -2.050034 25.925018 90)
			(size 0.519938 1.4986)
			(layers "F.Cu" "F.Mask" "F.Paste")
			(net "M_K_CPU0_SB_DQ<0>")
		)
		(pad "101" smd rect
			(at -2.050034 26.774902 90)
			(size 0.519938 1.4986)
			(layers "F.Cu" "F.Mask" "F.Paste")
			(net "GND")
		)
		(pad "102" smd rect
			(at -2.050034 27.62504 90)
			(size 0.519938 1.4986)
			(layers "F.Cu" "F.Mask" "F.Paste")
			(net "M_K_CPU0_SB_DQ<1>")
		)
		(pad "103" smd rect
			(at -2.050034 28.474924 90)
			(size 0.519938 1.4986)
			(layers "F.Cu" "F.Mask" "F.Paste")
			(net "GND")
		)
		(pad "104" smd rect
			(at -2.050034 29.325062 90)
			(size 0.519938 1.4986)
			(layers "F.Cu" "F.Mask" "F.Paste")
			(net "M_K_CPU0_SB_DQS_DP<0>")
		)
		(pad "105" smd rect
			(at -2.050034 30.174946 90)
			(size 0.519938 1.4986)
			(layers "F.Cu" "F.Mask" "F.Paste")
			(net "M_K_CPU0_SB_DQS_DN<0>")
		)
		(pad "106" smd rect
			(at -2.050034 31.025084 90)
			(size 0.519938 1.4986)
			(layers "F.Cu" "F.Mask" "F.Paste")
			(net "GND")
		)
		(pad "107" smd rect
			(at -2.050034 31.874968 90)
			(size 0.519938 1.4986)
			(layers "F.Cu" "F.Mask" "F.Paste")
			(net "M_K_CPU0_SB_DQ<4>")
		)
		(pad "108" smd rect
			(at -2.050034 32.725106 90)
			(size 0.519938 1.4986)
			(layers "F.Cu" "F.Mask" "F.Paste")
			(net "GND")
		)
		(pad "109" smd rect
			(at -2.050034 33.57499 90)
			(size 0.519938 1.4986)
			(layers "F.Cu" "F.Mask" "F.Paste")
			(net "M_K_CPU0_SB_DQ<5>")
		)
		(pad "110" smd rect
			(at -2.050034 34.425128 90)
			(size 0.519938 1.4986)
			(layers "F.Cu" "F.Mask" "F.Paste")
			(net "GND")
		)
		(pad "111" smd rect
			(at -2.050034 35.275012 90)
			(size 0.519938 1.4986)
			(layers "F.Cu" "F.Mask" "F.Paste")
			(net "M_K_CPU0_SB_DQ<8>")
		)
		(pad "112" smd rect
			(at -2.050034 36.124896 90)
			(size 0.519938 1.4986)
			(layers "F.Cu" "F.Mask" "F.Paste")
			(net "GND")
		)
		(pad "113" smd rect
			(at -2.050034 36.975034 90)
			(size 0.519938 1.4986)
			(layers "F.Cu" "F.Mask" "F.Paste")
			(net "M_K_CPU0_SB_DQ<9>")
		)
	)
)
